#ISCELL
  pure_quanta quanta_title_block_c *
  *
#ISCELL
  pure_quanta_power universal_gnd *
  page375_i1
#CELL
  pure_quanta mosfet_nch_dual *
  page375_i10
#CELL
  pure_quanta mosfet_nch_dual *
  page375_i11
#ISCELL
  pure_quanta_power universal_gnd *
  page375_i12
#CELL
  pure_quanta q_led *
  page375_i13
#CELL
  pure_quanta q_led *
  page375_i14
#CELL
  pure_quanta q_res *
  page375_i15
#CELL
  pure_quanta q_res *
  page375_i16
#CELL
  pure_quanta q_led *
  page375_i17
#CELL
  pure_quanta q_res *
  page375_i18
#CELL
  pure_quanta q_led *
  page375_i19
#CELL
  pure_quanta mosfet_nch_dual *
  page375_i2
#CELL
  pure_quanta q_res *
  page375_i20
#ISCELL
  pure_quanta_power universal_power *
  page375_i21
#ISCELL
  pure_quanta_power universal_power *
  page375_i22
#ISCELL
  standard offpage *
  page375_i25
#ISCELL
  pure_quanta_power universal_power *
  page375_i26
#ISCELL
  standard offpage *
  page375_i27
#ISCELL
  pure_quanta_power universal_gnd *
  page375_i28
#CELL
  pure_quanta mosfet_nch_dual *
  page375_i29
#ISCELL
  standard offpage *
  page375_i3
#CELL
  pure_quanta mosfet_nch_dual *
  page375_i30
#ISCELL
  pure_quanta_power universal_gnd *
  page375_i31
#CELL
  pure_quanta q_led *
  page375_i33
#ISCELL
  pure_quanta_power universal_power *
  page375_i34
#CELL
  pure_quanta q_led *
  page375_i35
#CELL
  pure_quanta q_res *
  page375_i38
#ISCELL
  pure_quanta_power universal_power *
  page375_i39
#ISCELL
  standard offpage *
  page375_i4
#CELL
  pure_quanta q_res *
  page375_i40
#ISCELL
  pure_quanta_power universal_power *
  page375_i41
#CELL
  pure_quanta q_led *
  page375_i42
#ISCELL
  pure_quanta_power universal_gnd *
  page375_i43
#CELL
  pure_quanta q_res *
  page375_i44
#CELL
  pure_quanta q_res *
  page375_i45
#CELL
  pure_quanta q_res *
  page375_i46
#ISCELL
  pure_quanta_power universal_power *
  page375_i47
#ISCELL
  pure_quanta_power universal_power *
  page375_i48
#CELL
  pure_quanta q_res *
  page375_i49
#ISCELL
  standard offpage *
  page375_i5
#CELL
  pure_quanta q_res *
  page375_i50
#CELL
  pure_quanta q_res *
  page375_i51
#CELL
  pure_quanta q_led *
  page375_i52
#ISCELL
  pure_quanta_power universal_gnd *
  page375_i53
#ISCELL
  pure_quanta_power universal_power *
  page375_i54
#CELL
  pure_quanta q_res *
  page375_i55
#CELL
  pure_quanta q_led *
  page375_i56
#CELL
  pure_quanta mosfet_nch_dual *
  page375_i57
#CELL
  pure_quanta mosfet_nch_dual *
  page375_i58
#ISCELL
  pure_quanta_power universal_gnd *
  page375_i59
#ISCELL
  standard offpage *
  page375_i6
#ISCELL
  pure_quanta_power universal_power *
  page375_i60
#ISCELL
  pure_quanta_power universal_gnd *
  page375_i61
#CELL
  pure_quanta q_res *
  page375_i62
#ISCELL
  standard offpage *
  page375_i63
#CELL
  pure_quanta mosfet_nch_dual *
  page375_i7
#ISCELL
  pure_quanta_power universal_gnd *
  page375_i8
#ISCELL
  pure_quanta_power universal_gnd *
  page375_i9
